# T6G (Grand Teton) — schematic netlist excerpt (pin names and nets, part order shuffled) for the footprints in the layout excerpt that follows; sources: Cadence DE-HDL packaged netlist, KiCad conversion of 04192023_DAF0TMB3IC0_F0TG_MB_C_brd_V02_OCP.brd

C6532  Q_CAP_DIFFBUS  DIFF BUS_0.22UF 6.3V 20% X6S  pkg C0201  page 275 : \1\ = P5E_CPU0_P0_TX_BUF_C_DN<15> ; \2\ = P5E_CPU0_P0_TX_BUF_DN<15>
C6522  Q_CAP_DIFFBUS  DIFF BUS_0.22UF 6.3V 20% X6S  pkg C0201  page 275 : \1\ = P5E_CPU0_P0_TX_BUF_C_DN<10> ; \2\ = P5E_CPU0_P0_TX_BUF_DN<10>
H102  HOLE  EMPTY  pkg TH  page 230 : \1\ = GND
PR3962  Q_RES  15K 1% CHIP  pkg 0402LF  page 146 : A = P12V_E1S_OV_0 ; B = GND

(kicad_pcb
	(version 20260206)
	(generator "pcbnew")
	(generator_version "10.0")
	(general
		(thickness 1.6)
		(legacy_teardrops no)
	)
	(paper "A4")
	(title_block
		(title "04192023_DAF0TMB3IC0_F0TG_MB_C_brd_V02_OCP.brd")
		(comment 1 "Grand Teton / footprints 2896-2899 of 8354")
	)
	(layers
		(0 "F.Cu" signal "TOP")
		(4 "In1.Cu" signal "GND")
		(6 "In2.Cu" signal "IN1")
		(8 "In3.Cu" signal "GND1")
		(10 "In4.Cu" signal "IN2")
		(12 "In5.Cu" signal "GND2")
		(14 "In6.Cu" signal "IN3")
		(16 "In7.Cu" signal "GND3")
		(18 "In8.Cu" signal "VCC")
		(20 "In9.Cu" signal "VCC1")
		(22 "In10.Cu" signal "GND4")
		(24 "In11.Cu" signal "IN4")
		(26 "In12.Cu" signal "GND5")
		(28 "In13.Cu" signal "IN5")
		(30 "In14.Cu" signal "GND6")
		(32 "In15.Cu" signal "IN6")
		(34 "In16.Cu" signal "GND7")
		(2 "B.Cu" signal "BOTTOM")
		(9 "F.Adhes" user "F.Adhesive")
		(11 "B.Adhes" user "B.Adhesive")
		(13 "F.Paste" user "Package Geometry/Pastemask Top")
		(15 "B.Paste" user "Package Geometry/Pastemask Bottom")
		(5 "F.SilkS" user "Ref Des/Silkscreen Top")
		(7 "B.SilkS" user "Ref Des/Silkscreen Bottom")
		(1 "F.Mask" user "Board Geometry/Soldermask Top")
		(3 "B.Mask" user "Board Geometry/Soldermask Bottom")
		(17 "Dwgs.User" user "User.Drawings")
		(19 "Cmts.User" user "User.Comments")
		(21 "Eco1.User" user "User.Eco1")
		(23 "Eco2.User" user "User.Eco2")
		(25 "Edge.Cuts" user "Board Geometry/Outline")
		(27 "Margin" user)
		(31 "F.CrtYd" user "Package Geometry/Place Bound Top")
		(29 "B.CrtYd" user "Package Geometry/Place Bound Bottom")
		(35 "F.Fab" user "Ref Des/Assembly Top")
		(33 "B.Fab" user "Ref Des/Assembly Bottom")
	)
	(footprint ""
		(layer "F.Cu")
		(at 249.28703 -45.995082 90)
		(property "Reference" "PR3962"
			(at 0 0 90)
			(layer "F.SilkS")
			(hide yes)
			(effects
				(font
					(size 1.27 1.27)
				)
			)
		)
		(property "Value" ""
			(at 0 0 90)
			(layer "F.Fab")
			(effects
				(font
					(size 1.27 1.27)
				)
			)
		)
		(duplicate_pad_numbers_are_jumpers no)
		(fp_line
			(start 0.7874 -0.4064)
			(end 0.7874 0.4064)
			(stroke
				(width 0.1524)
				(type default)
			)
			(layer "F.SilkS")
		)
		(fp_line
			(start -0.7874 -0.4064)
			(end 0.7874 -0.4064)
			(stroke
				(width 0.1524)
				(type default)
			)
			(layer "F.SilkS")
		)
		(fp_line
			(start 0.7874 0.4064)
			(end -0.7874 0.4064)
			(stroke
				(width 0.1524)
				(type default)
			)
			(layer "F.SilkS")
		)
		(fp_line
			(start -0.7874 0.4064)
			(end -0.7874 -0.4064)
			(stroke
				(width 0.1524)
				(type default)
			)
			(layer "F.SilkS")
		)
		(fp_line
			(start -0.12065 -0.305054)
			(end -0.12065 -0.2794)
			(stroke
				(width 0.1)
				(type default)
			)
			(layer "F.Fab")
		)
		(fp_line
			(start -0.67945 -0.305054)
			(end -0.12065 -0.305054)
			(stroke
				(width 0.1)
				(type default)
			)
			(layer "F.Fab")
		)
		(fp_line
			(start 0.67945 -0.3048)
			(end 0.67945 0.3048)
			(stroke
				(width 0.1)
				(type default)
			)
			(layer "F.Fab")
		)
		(fp_line
			(start 0.12065 -0.3048)
			(end 0.67945 -0.3048)
			(stroke
				(width 0.1)
				(type default)
			)
			(layer "F.Fab")
		)
		(fp_line
			(start 0.12065 -0.2794)
			(end 0.12065 -0.3048)
			(stroke
				(width 0.1)
				(type default)
			)
			(layer "F.Fab")
		)
		(fp_line
			(start -0.12065 -0.2794)
			(end 0.12065 -0.2794)
			(stroke
				(width 0.1)
				(type default)
			)
			(layer "F.Fab")
		)
		(fp_line
			(start 0.120396 0.2794)
			(end -0.12065 0.2794)
			(stroke
				(width 0.1)
				(type default)
			)
			(layer "F.Fab")
		)
		(fp_line
			(start -0.12065 0.2794)
			(end -0.12065 0.3048)
			(stroke
				(width 0.1)
				(type default)
			)
			(layer "F.Fab")
		)
		(fp_line
			(start 0.67945 0.3048)
			(end 0.120396 0.3048)
			(stroke
				(width 0.1)
				(type default)
			)
			(layer "F.Fab")
		)
		(fp_line
			(start 0.120396 0.3048)
			(end 0.120396 0.2794)
			(stroke
				(width 0.1)
				(type default)
			)
			(layer "F.Fab")
		)
		(fp_line
			(start -0.12065 0.3048)
			(end -0.67945 0.3048)
			(stroke
				(width 0.1)
				(type default)
			)
			(layer "F.Fab")
		)
		(fp_line
			(start -0.67945 0.3048)
			(end -0.67945 -0.305054)
			(stroke
				(width 0.1)
				(type default)
			)
			(layer "F.Fab")
		)
		(pad "1" smd circle
			(at -0.40005 0 90)
			(size 0 0)
			(layers "F.Cu" "F.Mask" "F.Paste")
			(net "P12V_E1S_OV_0")
		)
		(pad "2" smd circle
			(at 0.40005 0 90)
			(size 0 0)
			(layers "F.Cu" "F.Mask" "F.Paste")
			(net "GND")
		)
	)
	(footprint ""
		(layer "F.Cu")
		(at 334.400906 -416.899344 -90)
		(property "Reference" "C6522"
			(at 0 0 270)
			(layer "F.SilkS")
			(hide yes)
			(effects
				(font
					(size 1.27 1.27)
				)
			)
		)
		(property "Value" ""
			(at 0 0 270)
			(layer "F.Fab")
			(effects
				(font
					(size 1.27 1.27)
				)
			)
		)
		(duplicate_pad_numbers_are_jumpers no)
		(fp_line
			(start -0.299974 0.150114)
			(end -0.299974 -0.150114)
			(stroke
				(width 0.1)
				(type default)
			)
			(layer "F.Fab")
		)
		(fp_line
			(start 0.299974 0.150114)
			(end -0.299974 0.150114)
			(stroke
				(width 0.1)
				(type default)
			)
			(layer "F.Fab")
		)
		(fp_line
			(start -0.299974 -0.150114)
			(end 0.299974 -0.150114)
			(stroke
				(width 0.1)
				(type default)
			)
			(layer "F.Fab")
		)
		(fp_line
			(start 0.299974 -0.150114)
			(end 0.299974 0.150114)
			(stroke
				(width 0.1)
				(type default)
			)
			(layer "F.Fab")
		)
		(pad "1" smd rect
			(at -0.2667 0 270)
			(size 0.3048 0.381)
			(layers "F.Cu" "F.Mask" "F.Paste")
			(net "P5E_CPU0_P0_TX_BUF_C_DN<10>")
		)
		(pad "2" smd rect
			(at 0.2667 0 270)
			(size 0.3048 0.381)
			(layers "F.Cu" "F.Mask" "F.Paste")
			(net "P5E_CPU0_P0_TX_BUF_DN<10>")
		)
	)
	(footprint ""
		(layer "F.Cu")
		(at 10.339832 -347.702632)
		(property "Reference" "H102"
			(at -4.555998 -5.990336 0)
			(unlocked yes)
			(layer "F.SilkS")
			(effects
				(font
					(size 0.7874 0.5842)
					(thickness 0.1524)
				)
				(justify left)
			)
		)
		(property "Value" ""
			(at 0 0 0)
			(layer "F.Fab")
			(effects
				(font
					(size 1.27 1.27)
				)
			)
		)
		(duplicate_pad_numbers_are_jumpers no)
		(pad "1" thru_hole circle
			(at 0 0)
			(size 10.0076 10.0076)
			(drill 5.6134)
			(layers "*.Cu" "*.Mask")
			(remove_unused_layers no)
			(net "GND")
			(clearance -1.9431)
		)
	)
	(footprint ""
		(layer "F.Cu")
		(at 349.717106 -416.899344 -90)
		(property "Reference" "C6532"
			(at 0 0 270)
			(layer "F.SilkS")
			(hide yes)
			(effects
				(font
					(size 1.27 1.27)
				)
			)
		)
		(property "Value" ""
			(at 0 0 270)
			(layer "F.Fab")
			(effects
				(font
					(size 1.27 1.27)
				)
			)
		)
		(duplicate_pad_numbers_are_jumpers no)
		(fp_line
			(start -0.299974 0.150114)
			(end -0.299974 -0.150114)
			(stroke
				(width 0.1)
				(type default)
			)
			(layer "F.Fab")
		)
		(fp_line
			(start 0.299974 0.150114)
			(end -0.299974 0.150114)
			(stroke
				(width 0.1)
				(type default)
			)
			(layer "F.Fab")
		)
		(fp_line
			(start -0.299974 -0.150114)
			(end 0.299974 -0.150114)
			(stroke
				(width 0.1)
				(type default)
			)
			(layer "F.Fab")
		)
		(fp_line
			(start 0.299974 -0.150114)
			(end 0.299974 0.150114)
			(stroke
				(width 0.1)
				(type default)
			)
			(layer "F.Fab")
		)
		(pad "1" smd rect
			(at -0.2667 0 270)
			(size 0.3048 0.381)
			(layers "F.Cu" "F.Mask" "F.Paste")
			(net "P5E_CPU0_P0_TX_BUF_C_DN<15>")
		)
		(pad "2" smd rect
			(at 0.2667 0 270)
			(size 0.3048 0.381)
			(layers "F.Cu" "F.Mask" "F.Paste")
			(net "P5E_CPU0_P0_TX_BUF_DN<15>")
		)
	)
)
